# S9S_MB_2U (Grand Teton) — schematic netlist excerpt (pin names and nets, part order shuffled) for the footprints in the layout excerpt that follows; sources: Cadence DE-HDL packaged netlist, KiCad conversion of 03242023_DA0F0TMBIJ0_F0T_Motherboard_J_brd_V01_OCP.brd

R4052  Q_RES  33.2 1% CHIP  pkg 0402LF  page 225 : A = H_CPU_ERR2_LVC2_R_N ; B = H_CPU_ERR2_LVC2_N
R3617  Q_RES  4.7K 1% EMPTY  pkg 0402LF  page 171 : A = GND ; B = INA230_1_A0

(kicad_pcb
	(version 20260206)
	(generator "pcbnew")
	(generator_version "10.0")
	(general
		(thickness 1.6)
		(legacy_teardrops no)
	)
	(paper "A4")
	(title_block
		(title "03242023_DA0F0TMBIJ0_F0T_Motherboard_J_brd_V01_OCP.brd")
		(comment 1 "Grand Teton / footprints 3336-3337 of 6105")
	)
	(layers
		(0 "F.Cu" signal "TOP")
		(4 "In1.Cu" signal "GND")
		(6 "In2.Cu" signal "IN1")
		(8 "In3.Cu" signal "GND1")
		(10 "In4.Cu" signal "IN2")
		(12 "In5.Cu" signal "GND2")
		(14 "In6.Cu" signal "IN3")
		(16 "In7.Cu" signal "GND3")
		(18 "In8.Cu" signal "VCC")
		(20 "In9.Cu" signal "VCC1")
		(22 "In10.Cu" signal "GND4")
		(24 "In11.Cu" signal "IN4")
		(26 "In12.Cu" signal "GND5")
		(28 "In13.Cu" signal "IN5")
		(30 "In14.Cu" signal "GND6")
		(32 "In15.Cu" signal "IN6")
		(34 "In16.Cu" signal "GND7")
		(2 "B.Cu" signal "BOTTOM")
		(9 "F.Adhes" user "F.Adhesive")
		(11 "B.Adhes" user "B.Adhesive")
		(13 "F.Paste" user "Package Geometry/Pastemask Top")
		(15 "B.Paste" user "Package Geometry/Pastemask Bottom")
		(5 "F.SilkS" user "Ref Des/Silkscreen Top")
		(7 "B.SilkS" user "Ref Des/Silkscreen Bottom")
		(1 "F.Mask" user "Board Geometry/Soldermask Top")
		(3 "B.Mask" user "Board Geometry/Soldermask Bottom")
		(17 "Dwgs.User" user "User.Drawings")
		(19 "Cmts.User" user "User.Comments")
		(21 "Eco1.User" user "User.Eco1")
		(23 "Eco2.User" user "User.Eco2")
		(25 "Edge.Cuts" user "Board Geometry/Outline")
		(27 "Margin" user)
		(31 "F.CrtYd" user "Package Geometry/Place Bound Top")
		(29 "B.CrtYd" user "Package Geometry/Place Bound Bottom")
		(35 "F.Fab" user "Ref Des/Assembly Top")
		(33 "B.Fab" user "Ref Des/Assembly Bottom")
	)
	(footprint ""
		(layer "F.Cu")
		(at 448.672458 -93.509592 180)
		(property "Reference" "R3617"
			(at 0 0 180)
			(layer "F.SilkS")
			(hide yes)
			(effects
				(font
					(size 1.27 1.27)
				)
			)
		)
		(property "Value" ""
			(at 0 0 180)
			(layer "F.Fab")
			(effects
				(font
					(size 1.27 1.27)
				)
			)
		)
		(duplicate_pad_numbers_are_jumpers no)
		(fp_line
			(start 0.7874 0.4064)
			(end -0.7874 0.4064)
			(stroke
				(width 0.1524)
				(type default)
			)
			(layer "F.SilkS")
		)
		(fp_line
			(start 0.7874 -0.4064)
			(end 0.7874 0.4064)
			(stroke
				(width 0.1524)
				(type default)
			)
			(layer "F.SilkS")
		)
		(fp_line
			(start -0.7874 0.4064)
			(end -0.7874 -0.4064)
			(stroke
				(width 0.1524)
				(type default)
			)
			(layer "F.SilkS")
		)
		(fp_line
			(start -0.7874 -0.4064)
			(end 0.7874 -0.4064)
			(stroke
				(width 0.1524)
				(type default)
			)
			(layer "F.SilkS")
		)
		(fp_line
			(start 0.67945 0.3048)
			(end 0.120396 0.3048)
			(stroke
				(width 0.1)
				(type default)
			)
			(layer "F.Fab")
		)
		(fp_line
			(start 0.67945 -0.3048)
			(end 0.67945 0.3048)
			(stroke
				(width 0.1)
				(type default)
			)
			(layer "F.Fab")
		)
		(fp_line
			(start 0.12065 -0.2794)
			(end 0.12065 -0.3048)
			(stroke
				(width 0.1)
				(type default)
			)
			(layer "F.Fab")
		)
		(fp_line
			(start 0.12065 -0.3048)
			(end 0.67945 -0.3048)
			(stroke
				(width 0.1)
				(type default)
			)
			(layer "F.Fab")
		)
		(fp_line
			(start 0.120396 0.3048)
			(end 0.120396 0.2794)
			(stroke
				(width 0.1)
				(type default)
			)
			(layer "F.Fab")
		)
		(fp_line
			(start 0.120396 0.2794)
			(end -0.12065 0.2794)
			(stroke
				(width 0.1)
				(type default)
			)
			(layer "F.Fab")
		)
		(fp_line
			(start -0.12065 0.3048)
			(end -0.67945 0.3048)
			(stroke
				(width 0.1)
				(type default)
			)
			(layer "F.Fab")
		)
		(fp_line
			(start -0.12065 0.2794)
			(end -0.12065 0.3048)
			(stroke
				(width 0.1)
				(type default)
			)
			(layer "F.Fab")
		)
		(fp_line
			(start -0.12065 -0.2794)
			(end 0.12065 -0.2794)
			(stroke
				(width 0.1)
				(type default)
			)
			(layer "F.Fab")
		)
		(fp_line
			(start -0.12065 -0.305054)
			(end -0.12065 -0.2794)
			(stroke
				(width 0.1)
				(type default)
			)
			(layer "F.Fab")
		)
		(fp_line
			(start -0.67945 0.3048)
			(end -0.67945 -0.305054)
			(stroke
				(width 0.1)
				(type default)
			)
			(layer "F.Fab")
		)
		(fp_line
			(start -0.67945 -0.305054)
			(end -0.12065 -0.305054)
			(stroke
				(width 0.1)
				(type default)
			)
			(layer "F.Fab")
		)
		(pad "1" smd circle
			(at -0.40005 0 180)
			(size 0 0)
			(layers "F.Cu" "F.Mask" "F.Paste")
			(net "GND")
		)
		(pad "2" smd circle
			(at 0.40005 0 180)
			(size 0 0)
			(layers "F.Cu" "F.Mask" "F.Paste")
			(net "INA230_1_A0")
		)
	)
	(footprint ""
		(layer "F.Cu")
		(at 145.65884 -92.634308 -90)
		(property "Reference" "R4052"
			(at 0 0 270)
			(layer "F.SilkS")
			(hide yes)
			(effects
				(font
					(size 1.27 1.27)
				)
			)
		)
		(property "Value" ""
			(at 0 0 270)
			(layer "F.Fab")
			(effects
				(font
					(size 1.27 1.27)
				)
			)
		)
		(duplicate_pad_numbers_are_jumpers no)
		(fp_line
			(start -0.7874 0.4064)
			(end -0.7874 -0.4064)
			(stroke
				(width 0.1524)
				(type default)
			)
			(layer "F.SilkS")
		)
		(fp_line
			(start 0.7874 0.4064)
			(end -0.7874 0.4064)
			(stroke
				(width 0.1524)
				(type default)
			)
			(layer "F.SilkS")
		)
		(fp_line
			(start -0.7874 -0.4064)
			(end 0.7874 -0.4064)
			(stroke
				(width 0.1524)
				(type default)
			)
			(layer "F.SilkS")
		)
		(fp_line
			(start 0.7874 -0.4064)
			(end 0.7874 0.4064)
			(stroke
				(width 0.1524)
				(type default)
			)
			(layer "F.SilkS")
		)
		(fp_line
			(start -0.67945 0.3048)
			(end -0.67945 -0.305054)
			(stroke
				(width 0.1)
				(type default)
			)
			(layer "F.Fab")
		)
		(fp_line
			(start -0.12065 0.3048)
			(end -0.67945 0.3048)
			(stroke
				(width 0.1)
				(type default)
			)
			(layer "F.Fab")
		)
		(fp_line
			(start 0.120396 0.3048)
			(end 0.120396 0.2794)
			(stroke
				(width 0.1)
				(type default)
			)
			(layer "F.Fab")
		)
		(fp_line
			(start 0.67945 0.3048)
			(end 0.120396 0.3048)
			(stroke
				(width 0.1)
				(type default)
			)
			(layer "F.Fab")
		)
		(fp_line
			(start -0.12065 0.2794)
			(end -0.12065 0.3048)
			(stroke
				(width 0.1)
				(type default)
			)
			(layer "F.Fab")
		)
		(fp_line
			(start 0.120396 0.2794)
			(end -0.12065 0.2794)
			(stroke
				(width 0.1)
				(type default)
			)
			(layer "F.Fab")
		)
		(fp_line
			(start -0.12065 -0.2794)
			(end 0.12065 -0.2794)
			(stroke
				(width 0.1)
				(type default)
			)
			(layer "F.Fab")
		)
		(fp_line
			(start 0.12065 -0.2794)
			(end 0.12065 -0.3048)
			(stroke
				(width 0.1)
				(type default)
			)
			(layer "F.Fab")
		)
		(fp_line
			(start 0.12065 -0.3048)
			(end 0.67945 -0.3048)
			(stroke
				(width 0.1)
				(type default)
			)
			(layer "F.Fab")
		)
		(fp_line
			(start 0.67945 -0.3048)
			(end 0.67945 0.3048)
			(stroke
				(width 0.1)
				(type default)
			)
			(layer "F.Fab")
		)
		(fp_line
			(start -0.67945 -0.305054)
			(end -0.12065 -0.305054)
			(stroke
				(width 0.1)
				(type default)
			)
			(layer "F.Fab")
		)
		(fp_line
			(start -0.12065 -0.305054)
			(end -0.12065 -0.2794)
			(stroke
				(width 0.1)
				(type default)
			)
			(layer "F.Fab")
		)
		(pad "1" smd circle
			(at -0.40005 0 270)
			(size 0 0)
			(layers "F.Cu" "F.Mask" "F.Paste")
			(net "H_CPU_ERR2_LVC2_R_N")
		)
		(pad "2" smd circle
			(at 0.40005 0 270)
			(size 0 0)
			(layers "F.Cu" "F.Mask" "F.Paste")
			(net "H_CPU_ERR2_LVC2_N")
		)
	)
)
